# S9S_MB_2U (Grand Teton) — schematic netlist excerpt (pin names and nets, part order shuffled) for the footprints in the layout excerpt that follows; sources: Cadence DE-HDL packaged netlist, KiCad conversion of 03242023_DA0F0TMBIJ0_F0T_Motherboard_J_brd_V01_OCP.brd

R2984  Q_RES  10K 1% CHIP  pkg 0402LF  page 231 : A = P3V3_AUX ; B = SMB_BMC_SWB_SCL
R4396  Q_RES  100 1% CHIP  pkg 0402LF  page 121 : A = PVNN_TERM_CPU1 ; B = H_CPU1_THERMTRIP_LVC1_R_N

(kicad_pcb
	(version 20260206)
	(generator "pcbnew")
	(generator_version "10.0")
	(general
		(thickness 1.6)
		(legacy_teardrops no)
	)
	(paper "A4")
	(title_block
		(title "03242023_DA0F0TMBIJ0_F0T_Motherboard_J_brd_V01_OCP.brd")
		(comment 1 "Grand Teton / footprints 3722-3723 of 6105")
	)
	(layers
		(0 "F.Cu" signal "TOP")
		(4 "In1.Cu" signal "GND")
		(6 "In2.Cu" signal "IN1")
		(8 "In3.Cu" signal "GND1")
		(10 "In4.Cu" signal "IN2")
		(12 "In5.Cu" signal "GND2")
		(14 "In6.Cu" signal "IN3")
		(16 "In7.Cu" signal "GND3")
		(18 "In8.Cu" signal "VCC")
		(20 "In9.Cu" signal "VCC1")
		(22 "In10.Cu" signal "GND4")
		(24 "In11.Cu" signal "IN4")
		(26 "In12.Cu" signal "GND5")
		(28 "In13.Cu" signal "IN5")
		(30 "In14.Cu" signal "GND6")
		(32 "In15.Cu" signal "IN6")
		(34 "In16.Cu" signal "GND7")
		(2 "B.Cu" signal "BOTTOM")
		(9 "F.Adhes" user "F.Adhesive")
		(11 "B.Adhes" user "B.Adhesive")
		(13 "F.Paste" user "Package Geometry/Pastemask Top")
		(15 "B.Paste" user "Package Geometry/Pastemask Bottom")
		(5 "F.SilkS" user "Ref Des/Silkscreen Top")
		(7 "B.SilkS" user "Ref Des/Silkscreen Bottom")
		(1 "F.Mask" user "Board Geometry/Soldermask Top")
		(3 "B.Mask" user "Board Geometry/Soldermask Bottom")
		(17 "Dwgs.User" user "User.Drawings")
		(19 "Cmts.User" user "User.Comments")
		(21 "Eco1.User" user "User.Eco1")
		(23 "Eco2.User" user "User.Eco2")
		(25 "Edge.Cuts" user "Board Geometry/Outline")
		(27 "Margin" user)
		(31 "F.CrtYd" user "Package Geometry/Place Bound Top")
		(29 "B.CrtYd" user "Package Geometry/Place Bound Bottom")
		(35 "F.Fab" user "Ref Des/Assembly Top")
		(33 "B.Fab" user "Ref Des/Assembly Bottom")
	)
	(footprint ""
		(layer "F.Cu")
		(at 131.466844 -128.516126 180)
		(property "Reference" "R2984"
			(at 0 0 180)
			(layer "F.SilkS")
			(hide yes)
			(effects
				(font
					(size 1.27 1.27)
				)
			)
		)
		(property "Value" ""
			(at 0 0 180)
			(layer "F.Fab")
			(effects
				(font
					(size 1.27 1.27)
				)
			)
		)
		(duplicate_pad_numbers_are_jumpers no)
		(fp_line
			(start 0.7874 0.4064)
			(end -0.7874 0.4064)
			(stroke
				(width 0.1524)
				(type default)
			)
			(layer "F.SilkS")
		)
		(fp_line
			(start 0.7874 -0.4064)
			(end 0.7874 0.4064)
			(stroke
				(width 0.1524)
				(type default)
			)
			(layer "F.SilkS")
		)
		(fp_line
			(start -0.7874 0.4064)
			(end -0.7874 -0.4064)
			(stroke
				(width 0.1524)
				(type default)
			)
			(layer "F.SilkS")
		)
		(fp_line
			(start -0.7874 -0.4064)
			(end 0.7874 -0.4064)
			(stroke
				(width 0.1524)
				(type default)
			)
			(layer "F.SilkS")
		)
		(fp_line
			(start 0.67945 0.3048)
			(end 0.120396 0.3048)
			(stroke
				(width 0.1)
				(type default)
			)
			(layer "F.Fab")
		)
		(fp_line
			(start 0.67945 -0.3048)
			(end 0.67945 0.3048)
			(stroke
				(width 0.1)
				(type default)
			)
			(layer "F.Fab")
		)
		(fp_line
			(start 0.12065 -0.2794)
			(end 0.12065 -0.3048)
			(stroke
				(width 0.1)
				(type default)
			)
			(layer "F.Fab")
		)
		(fp_line
			(start 0.12065 -0.3048)
			(end 0.67945 -0.3048)
			(stroke
				(width 0.1)
				(type default)
			)
			(layer "F.Fab")
		)
		(fp_line
			(start 0.120396 0.3048)
			(end 0.120396 0.2794)
			(stroke
				(width 0.1)
				(type default)
			)
			(layer "F.Fab")
		)
		(fp_line
			(start 0.120396 0.2794)
			(end -0.12065 0.2794)
			(stroke
				(width 0.1)
				(type default)
			)
			(layer "F.Fab")
		)
		(fp_line
			(start -0.12065 0.3048)
			(end -0.67945 0.3048)
			(stroke
				(width 0.1)
				(type default)
			)
			(layer "F.Fab")
		)
		(fp_line
			(start -0.12065 0.2794)
			(end -0.12065 0.3048)
			(stroke
				(width 0.1)
				(type default)
			)
			(layer "F.Fab")
		)
		(fp_line
			(start -0.12065 -0.2794)
			(end 0.12065 -0.2794)
			(stroke
				(width 0.1)
				(type default)
			)
			(layer "F.Fab")
		)
		(fp_line
			(start -0.12065 -0.305054)
			(end -0.12065 -0.2794)
			(stroke
				(width 0.1)
				(type default)
			)
			(layer "F.Fab")
		)
		(fp_line
			(start -0.67945 0.3048)
			(end -0.67945 -0.305054)
			(stroke
				(width 0.1)
				(type default)
			)
			(layer "F.Fab")
		)
		(fp_line
			(start -0.67945 -0.305054)
			(end -0.12065 -0.305054)
			(stroke
				(width 0.1)
				(type default)
			)
			(layer "F.Fab")
		)
		(pad "1" smd circle
			(at -0.40005 0 180)
			(size 0 0)
			(layers "F.Cu" "F.Mask" "F.Paste")
			(net "P3V3_AUX")
		)
		(pad "2" smd circle
			(at 0.40005 0 180)
			(size 0 0)
			(layers "F.Cu" "F.Mask" "F.Paste")
			(net "SMB_BMC_SWB_SCL")
		)
	)
	(footprint ""
		(layer "F.Cu")
		(at 124.64288 -92.674948 -90)
		(property "Reference" "R4396"
			(at 0 0 270)
			(layer "F.SilkS")
			(hide yes)
			(effects
				(font
					(size 1.27 1.27)
				)
			)
		)
		(property "Value" ""
			(at 0 0 270)
			(layer "F.Fab")
			(effects
				(font
					(size 1.27 1.27)
				)
			)
		)
		(duplicate_pad_numbers_are_jumpers no)
		(fp_line
			(start -0.7874 0.4064)
			(end -0.7874 -0.4064)
			(stroke
				(width 0.1524)
				(type default)
			)
			(layer "F.SilkS")
		)
		(fp_line
			(start 0.7874 0.4064)
			(end -0.7874 0.4064)
			(stroke
				(width 0.1524)
				(type default)
			)
			(layer "F.SilkS")
		)
		(fp_line
			(start -0.7874 -0.4064)
			(end 0.7874 -0.4064)
			(stroke
				(width 0.1524)
				(type default)
			)
			(layer "F.SilkS")
		)
		(fp_line
			(start 0.7874 -0.4064)
			(end 0.7874 0.4064)
			(stroke
				(width 0.1524)
				(type default)
			)
			(layer "F.SilkS")
		)
		(fp_line
			(start -0.67945 0.3048)
			(end -0.67945 -0.305054)
			(stroke
				(width 0.1)
				(type default)
			)
			(layer "F.Fab")
		)
		(fp_line
			(start -0.12065 0.3048)
			(end -0.67945 0.3048)
			(stroke
				(width 0.1)
				(type default)
			)
			(layer "F.Fab")
		)
		(fp_line
			(start 0.120396 0.3048)
			(end 0.120396 0.2794)
			(stroke
				(width 0.1)
				(type default)
			)
			(layer "F.Fab")
		)
		(fp_line
			(start 0.67945 0.3048)
			(end 0.120396 0.3048)
			(stroke
				(width 0.1)
				(type default)
			)
			(layer "F.Fab")
		)
		(fp_line
			(start -0.12065 0.2794)
			(end -0.12065 0.3048)
			(stroke
				(width 0.1)
				(type default)
			)
			(layer "F.Fab")
		)
		(fp_line
			(start 0.120396 0.2794)
			(end -0.12065 0.2794)
			(stroke
				(width 0.1)
				(type default)
			)
			(layer "F.Fab")
		)
		(fp_line
			(start -0.12065 -0.2794)
			(end 0.12065 -0.2794)
			(stroke
				(width 0.1)
				(type default)
			)
			(layer "F.Fab")
		)
		(fp_line
			(start 0.12065 -0.2794)
			(end 0.12065 -0.3048)
			(stroke
				(width 0.1)
				(type default)
			)
			(layer "F.Fab")
		)
		(fp_line
			(start 0.12065 -0.3048)
			(end 0.67945 -0.3048)
			(stroke
				(width 0.1)
				(type default)
			)
			(layer "F.Fab")
		)
		(fp_line
			(start 0.67945 -0.3048)
			(end 0.67945 0.3048)
			(stroke
				(width 0.1)
				(type default)
			)
			(layer "F.Fab")
		)
		(fp_line
			(start -0.67945 -0.305054)
			(end -0.12065 -0.305054)
			(stroke
				(width 0.1)
				(type default)
			)
			(layer "F.Fab")
		)
		(fp_line
			(start -0.12065 -0.305054)
			(end -0.12065 -0.2794)
			(stroke
				(width 0.1)
				(type default)
			)
			(layer "F.Fab")
		)
		(pad "1" smd circle
			(at -0.40005 0 270)
			(size 0 0)
			(layers "F.Cu" "F.Mask" "F.Paste")
			(net "PVNN_TERM_CPU1")
		)
		(pad "2" smd circle
			(at 0.40005 0 270)
			(size 0 0)
			(layers "F.Cu" "F.Mask" "F.Paste")
			(net "H_CPU1_THERMTRIP_LVC1_R_N")
		)
	)
)
